(kicad_pcb
	(version 20260206)
	(generator "pcbnew")
	(generator_version "10.0")
	(general
		(thickness 1.6)
		(legacy_teardrops no)
	)
	(paper "A4")
	(title_block
		(title "04192023_DAF0TMB3IC0_F0TG_MB_C_brd_V02_OCP.brd")
		(comment 1 "Grand Teton / footprints 3872-3877 of 8354")
	)
	(layers
		(0 "F.Cu" signal "TOP")
		(4 "In1.Cu" signal "GND")
		(6 "In2.Cu" signal "IN1")
		(8 "In3.Cu" signal "GND1")
		(10 "In4.Cu" signal "IN2")
		(12 "In5.Cu" signal "GND2")
		(14 "In6.Cu" signal "IN3")
		(16 "In7.Cu" signal "GND3")
		(18 "In8.Cu" signal "VCC")
		(20 "In9.Cu" signal "VCC1")
		(22 "In10.Cu" signal "GND4")
		(24 "In11.Cu" signal "IN4")
		(26 "In12.Cu" signal "GND5")
		(28 "In13.Cu" signal "IN5")
		(30 "In14.Cu" signal "GND6")
		(32 "In15.Cu" signal "IN6")
		(34 "In16.Cu" signal "GND7")
		(2 "B.Cu" signal "BOTTOM")
		(9 "F.Adhes" user "F.Adhesive")
		(11 "B.Adhes" user "B.Adhesive")
		(13 "F.Paste" user "Package Geometry/Pastemask Top")
		(15 "B.Paste" user "Package Geometry/Pastemask Bottom")
		(5 "F.SilkS" user "Ref Des/Silkscreen Top")
		(7 "B.SilkS" user "Ref Des/Silkscreen Bottom")
		(1 "F.Mask" user "Board Geometry/Soldermask Top")
		(3 "B.Mask" user "Board Geometry/Soldermask Bottom")
		(17 "Dwgs.User" user "User.Drawings")
		(19 "Cmts.User" user "User.Comments")
		(21 "Eco1.User" user "User.Eco1")
		(23 "Eco2.User" user "User.Eco2")
		(25 "Edge.Cuts" user "Board Geometry/Outline")
		(27 "Margin" user)
		(31 "F.CrtYd" user "Package Geometry/Place Bound Top")
		(29 "B.CrtYd" user "Package Geometry/Place Bound Bottom")
		(35 "F.Fab" user "Ref Des/Assembly Top")
		(33 "B.Fab" user "Ref Des/Assembly Bottom")
	)
	(footprint ""
		(layer "F.Cu")
		(at 22.036278 -437.980074)
		(property "Reference" "R3108"
			(at 0 0 0)
			(layer "F.SilkS")
			(hide yes)
			(effects
				(font
					(size 1.27 1.27)
				)
			)
		)
		(property "Value" ""
			(at 0 0 0)
			(layer "F.Fab")
			(effects
				(font
					(size 1.27 1.27)
				)
			)
		)
		(duplicate_pad_numbers_are_jumpers no)
		(fp_line
			(start -0.7874 -0.4064)
			(end 0.7874 -0.4064)
			(stroke
				(width 0.1524)
				(type default)
			)
			(layer "F.SilkS")
		)
		(fp_line
			(start -0.7874 0.4064)
			(end -0.7874 -0.4064)
			(stroke
				(width 0.1524)
				(type default)
			)
			(layer "F.SilkS")
		)
		(fp_line
			(start 0.7874 -0.4064)
			(end 0.7874 0.4064)
			(stroke
				(width 0.1524)
				(type default)
			)
			(layer "F.SilkS")
		)
		(fp_line
			(start 0.7874 0.4064)
			(end -0.7874 0.4064)
			(stroke
				(width 0.1524)
				(type default)
			)
			(layer "F.SilkS")
		)
		(fp_line
			(start -0.67945 -0.305054)
			(end -0.12065 -0.305054)
			(stroke
				(width 0.1)
				(type default)
			)
			(layer "F.Fab")
		)
		(fp_line
			(start -0.67945 0.3048)
			(end -0.67945 -0.305054)
			(stroke
				(width 0.1)
				(type default)
			)
			(layer "F.Fab")
		)
		(fp_line
			(start -0.12065 -0.305054)
			(end -0.12065 -0.2794)
			(stroke
				(width 0.1)
				(type default)
			)
			(layer "F.Fab")
		)
		(fp_line
			(start -0.12065 -0.2794)
			(end 0.12065 -0.2794)
			(stroke
				(width 0.1)
				(type default)
			)
			(layer "F.Fab")
		)
		(fp_line
			(start -0.12065 0.2794)
			(end -0.12065 0.3048)
			(stroke
				(width 0.1)
				(type default)
			)
			(layer "F.Fab")
		)
		(fp_line
			(start -0.12065 0.3048)
			(end -0.67945 0.3048)
			(stroke
				(width 0.1)
				(type default)
			)
			(layer "F.Fab")
		)
		(fp_line
			(start 0.120396 0.2794)
			(end -0.12065 0.2794)
			(stroke
				(width 0.1)
				(type default)
			)
			(layer "F.Fab")
		)
		(fp_line
			(start 0.120396 0.3048)
			(end 0.120396 0.2794)
			(stroke
				(width 0.1)
				(type default)
			)
			(layer "F.Fab")
		)
		(fp_line
			(start 0.12065 -0.3048)
			(end 0.67945 -0.3048)
			(stroke
				(width 0.1)
				(type default)
			)
			(layer "F.Fab")
		)
		(fp_line
			(start 0.12065 -0.2794)
			(end 0.12065 -0.3048)
			(stroke
				(width 0.1)
				(type default)
			)
			(layer "F.Fab")
		)
		(fp_line
			(start 0.67945 -0.3048)
			(end 0.67945 0.3048)
			(stroke
				(width 0.1)
				(type default)
			)
			(layer "F.Fab")
		)
		(fp_line
			(start 0.67945 0.3048)
			(end 0.120396 0.3048)
			(stroke
				(width 0.1)
				(type default)
			)
			(layer "F.Fab")
		)
		(pad "1" smd circle
			(at -0.40005 0)
			(size 0 0)
			(layers "F.Cu" "F.Mask" "F.Paste")
			(net "SMB_2_BMC_GPU_SDA")
		)
		(pad "2" smd circle
			(at 0.40005 0)
			(size 0 0)
			(layers "F.Cu" "F.Mask" "F.Paste")
			(net "SMB_2_BMC_GPU_R_SDA")
		)
	)
	(footprint ""
		(layer "F.Cu")
		(at 204.994764 -96.77908)
		(property "Reference" "R1133"
			(at 0 0 0)
			(layer "F.SilkS")
			(hide yes)
			(effects
				(font
					(size 1.27 1.27)
				)
			)
		)
		(property "Value" ""
			(at 0 0 0)
			(layer "F.Fab")
			(effects
				(font
					(size 1.27 1.27)
				)
			)
		)
		(duplicate_pad_numbers_are_jumpers no)
		(fp_line
			(start -0.7874 -0.4064)
			(end 0.7874 -0.4064)
			(stroke
				(width 0.1524)
				(type default)
			)
			(layer "F.SilkS")
		)
		(fp_line
			(start -0.7874 0.4064)
			(end -0.7874 -0.4064)
			(stroke
				(width 0.1524)
				(type default)
			)
			(layer "F.SilkS")
		)
		(fp_line
			(start 0.7874 -0.4064)
			(end 0.7874 0.4064)
			(stroke
				(width 0.1524)
				(type default)
			)
			(layer "F.SilkS")
		)
		(fp_line
			(start 0.7874 0.4064)
			(end -0.7874 0.4064)
			(stroke
				(width 0.1524)
				(type default)
			)
			(layer "F.SilkS")
		)
		(fp_line
			(start -0.67945 -0.305054)
			(end -0.12065 -0.305054)
			(stroke
				(width 0.1)
				(type default)
			)
			(layer "F.Fab")
		)
		(fp_line
			(start -0.67945 0.3048)
			(end -0.67945 -0.305054)
			(stroke
				(width 0.1)
				(type default)
			)
			(layer "F.Fab")
		)
		(fp_line
			(start -0.12065 -0.305054)
			(end -0.12065 -0.2794)
			(stroke
				(width 0.1)
				(type default)
			)
			(layer "F.Fab")
		)
		(fp_line
			(start -0.12065 -0.2794)
			(end 0.12065 -0.2794)
			(stroke
				(width 0.1)
				(type default)
			)
			(layer "F.Fab")
		)
		(fp_line
			(start -0.12065 0.2794)
			(end -0.12065 0.3048)
			(stroke
				(width 0.1)
				(type default)
			)
			(layer "F.Fab")
		)
		(fp_line
			(start -0.12065 0.3048)
			(end -0.67945 0.3048)
			(stroke
				(width 0.1)
				(type default)
			)
			(layer "F.Fab")
		)
		(fp_line
			(start 0.120396 0.2794)
			(end -0.12065 0.2794)
			(stroke
				(width 0.1)
				(type default)
			)
			(layer "F.Fab")
		)
		(fp_line
			(start 0.120396 0.3048)
			(end 0.120396 0.2794)
			(stroke
				(width 0.1)
				(type default)
			)
			(layer "F.Fab")
		)
		(fp_line
			(start 0.12065 -0.3048)
			(end 0.67945 -0.3048)
			(stroke
				(width 0.1)
				(type default)
			)
			(layer "F.Fab")
		)
		(fp_line
			(start 0.12065 -0.2794)
			(end 0.12065 -0.3048)
			(stroke
				(width 0.1)
				(type default)
			)
			(layer "F.Fab")
		)
		(fp_line
			(start 0.67945 -0.3048)
			(end 0.67945 0.3048)
			(stroke
				(width 0.1)
				(type default)
			)
			(layer "F.Fab")
		)
		(fp_line
			(start 0.67945 0.3048)
			(end 0.120396 0.3048)
			(stroke
				(width 0.1)
				(type default)
			)
			(layer "F.Fab")
		)
		(pad "1" smd circle
			(at -0.40005 0)
			(size 0 0)
			(layers "F.Cu" "F.Mask" "F.Paste")
			(net "P3V3_AUX")
		)
		(pad "2" smd circle
			(at 0.40005 0)
			(size 0 0)
			(layers "F.Cu" "F.Mask" "F.Paste")
			(net "P12V_OCP_V3_1_PLD_PWRGD")
		)
	)
	(footprint ""
		(layer "F.Cu")
		(at 216.18575 -43.738292 180)
		(property "Reference" "U279"
			(at 0.6731 2.330704 0)
			(unlocked yes)
			(layer "F.SilkS")
			(effects
				(font
					(size 0.7874 0.5842)
					(thickness 0.1524)
				)
				(justify left)
			)
		)
		(property "Value" ""
			(at 0 0 180)
			(layer "F.Fab")
			(effects
				(font
					(size 1.27 1.27)
				)
			)
		)
		(duplicate_pad_numbers_are_jumpers no)
		(fp_line
			(start 1.463548 1.549908)
			(end -1.463548 1.549908)
			(stroke
				(width 0.1524)
				(type default)
			)
			(layer "F.SilkS")
		)
		(fp_line
			(start 1.463548 -1.549908)
			(end 1.463548 1.549908)
			(stroke
				(width 0.1524)
				(type default)
			)
			(layer "F.SilkS")
		)
		(fp_line
			(start 0.762 -1.549908)
			(end 1.463548 -1.549908)
			(stroke
				(width 0.1524)
				(type default)
			)
			(layer "F.SilkS")
		)
		(fp_line
			(start 0 -0.762)
			(end 0.762 -1.549908)
			(stroke
				(width 0.1524)
				(type default)
			)
			(layer "F.SilkS")
		)
		(fp_line
			(start -0.787908 -1.549908)
			(end 0 -0.762)
			(stroke
				(width 0.1524)
				(type default)
			)
			(layer "F.SilkS")
		)
		(fp_line
			(start -1.463548 1.549908)
			(end -1.463548 -1.549908)
			(stroke
				(width 0.1524)
				(type default)
			)
			(layer "F.SilkS")
		)
		(fp_line
			(start -1.463548 -1.549908)
			(end -0.787908 -1.549908)
			(stroke
				(width 0.1524)
				(type default)
			)
			(layer "F.SilkS")
		)
		(fp_poly
			(pts
				(xy -2.453386 -2.164842) (xy -1.833626 -2.164842) (xy -2.143506 -1.545082)
			)
			(stroke
				(width 0)
				(type default)
			)
			(fill yes)
			(layer "F.SilkS")
		)
		(fp_line
			(start 1.549908 1.549908)
			(end -1.549908 1.549908)
			(stroke
				(width 0.1)
				(type default)
			)
			(layer "F.Fab")
		)
		(fp_line
			(start 1.549908 -1.549908)
			(end 1.549908 1.549908)
			(stroke
				(width 0.1)
				(type default)
			)
			(layer "F.Fab")
		)
		(fp_line
			(start -1.549908 1.549908)
			(end -1.549908 -1.549908)
			(stroke
				(width 0.1)
				(type default)
			)
			(layer "F.Fab")
		)
		(fp_line
			(start -1.549908 -1.549908)
			(end 1.549908 -1.549908)
			(stroke
				(width 0.1)
				(type default)
			)
			(layer "F.Fab")
		)
		(fp_poly
			(pts
				(xy -3.4798 -1.359916) (xy -2.86004 -1.050036) (xy -3.4798 -0.740156)
			)
			(stroke
				(width 0)
				(type default)
			)
			(fill yes)
			(layer "F.Fab")
		)
		(pad "1" smd rect
			(at -2.175002 -1.050036 270)
			(size 0.6096 1.1684)
			(layers "F.Cu" "F.Mask" "F.Paste")
			(net "P3V3_E1S_0")
		)
		(pad "2" smd rect
			(at -2.175002 -0.32512 270)
			(size 0.4318 1.1684)
			(layers "F.Cu" "F.Mask" "F.Paste")
			(net "SMB_E1S_3V3AUX_ISO_SCL_R")
		)
		(pad "3" smd rect
			(at -2.175002 0.32512 270)
			(size 0.4318 1.1684)
			(layers "F.Cu" "F.Mask" "F.Paste")
			(net "SMB_E1S_3V3AUX_ISO_SDA_R")
		)
		(pad "4" smd rect
			(at -2.175002 1.050036 270)
			(size 0.6096 1.1684)
			(layers "F.Cu" "F.Mask" "F.Paste")
			(net "GND")
		)
		(pad "5" smd rect
			(at 2.175002 1.050036 270)
			(size 0.6096 1.1684)
			(layers "F.Cu" "F.Mask" "F.Paste")
			(net "SMB_PCIE_E1S_ISO_EN_R")
		)
		(pad "6" smd rect
			(at 2.175002 0.32512 270)
			(size 0.4318 1.1684)
			(layers "F.Cu" "F.Mask" "F.Paste")
			(net "SMB_SENSOR_E1S_3V3AUX_SDA")
		)
		(pad "7" smd rect
			(at 2.175002 -0.32512 270)
			(size 0.4318 1.1684)
			(layers "F.Cu" "F.Mask" "F.Paste")
			(net "SMB_SENSOR_E1S_3V3AUX_SCL")
		)
		(pad "8" smd rect
			(at 2.175002 -1.050036 270)
			(size 0.6096 1.1684)
			(layers "F.Cu" "F.Mask" "F.Paste")
			(net "P3V3_AUX")
		)
	)
	(footprint ""
		(layer "F.Cu")
		(at 314.651898 -331.990954 180)
		(property "Reference" "PC192"
			(at 0 0 180)
			(layer "F.SilkS")
			(hide yes)
			(effects
				(font
					(size 1.27 1.27)
				)
			)
		)
		(property "Value" ""
			(at 0 0 180)
			(layer "F.Fab")
			(effects
				(font
					(size 1.27 1.27)
				)
			)
		)
		(duplicate_pad_numbers_are_jumpers no)
		(fp_line
			(start 0.7874 0.4064)
			(end -0.7874 0.4064)
			(stroke
				(width 0.1524)
				(type default)
			)
			(layer "F.SilkS")
		)
		(fp_line
			(start 0.7874 -0.4064)
			(end 0.7874 0.4064)
			(stroke
				(width 0.1524)
				(type default)
			)
			(layer "F.SilkS")
		)
		(fp_line
			(start -0.7874 0.4064)
			(end -0.7874 -0.4064)
			(stroke
				(width 0.1524)
				(type default)
			)
			(layer "F.SilkS")
		)
		(fp_line
			(start -0.7874 -0.4064)
			(end 0.7874 -0.4064)
			(stroke
				(width 0.1524)
				(type default)
			)
			(layer "F.SilkS")
		)
		(fp_line
			(start 0.67945 0.3048)
			(end 0.120396 0.3048)
			(stroke
				(width 0.1)
				(type default)
			)
			(layer "F.Fab")
		)
		(fp_line
			(start 0.67945 -0.3048)
			(end 0.67945 0.3048)
			(stroke
				(width 0.1)
				(type default)
			)
			(layer "F.Fab")
		)
		(fp_line
			(start 0.12065 -0.2794)
			(end 0.12065 -0.3048)
			(stroke
				(width 0.1)
				(type default)
			)
			(layer "F.Fab")
		)
		(fp_line
			(start 0.12065 -0.3048)
			(end 0.67945 -0.3048)
			(stroke
				(width 0.1)
				(type default)
			)
			(layer "F.Fab")
		)
		(fp_line
			(start 0.120396 0.3048)
			(end 0.120396 0.2794)
			(stroke
				(width 0.1)
				(type default)
			)
			(layer "F.Fab")
		)
		(fp_line
			(start 0.120396 0.2794)
			(end -0.12065 0.2794)
			(stroke
				(width 0.1)
				(type default)
			)
			(layer "F.Fab")
		)
		(fp_line
			(start -0.12065 0.3048)
			(end -0.67945 0.3048)
			(stroke
				(width 0.1)
				(type default)
			)
			(layer "F.Fab")
		)
		(fp_line
			(start -0.12065 0.2794)
			(end -0.12065 0.3048)
			(stroke
				(width 0.1)
				(type default)
			)
			(layer "F.Fab")
		)
		(fp_line
			(start -0.12065 -0.2794)
			(end 0.12065 -0.2794)
			(stroke
				(width 0.1)
				(type default)
			)
			(layer "F.Fab")
		)
		(fp_line
			(start -0.12065 -0.305054)
			(end -0.12065 -0.2794)
			(stroke
				(width 0.1)
				(type default)
			)
			(layer "F.Fab")
		)
		(fp_line
			(start -0.67945 0.3048)
			(end -0.67945 -0.305054)
			(stroke
				(width 0.1)
				(type default)
			)
			(layer "F.Fab")
		)
		(fp_line
			(start -0.67945 -0.305054)
			(end -0.12065 -0.305054)
			(stroke
				(width 0.1)
				(type default)
			)
			(layer "F.Fab")
		)
		(pad "1" smd circle
			(at -0.40005 0 180)
			(size 0 0)
			(layers "F.Cu" "F.Mask" "F.Paste")
			(net "SW_PVDDCR_CPU1_P0_SW3")
		)
		(pad "2" smd circle
			(at 0.40005 0 180)
			(size 0 0)
			(layers "F.Cu" "F.Mask" "F.Paste")
			(net "SW_PVDDCR_CPU1_P0_SW3_RC")
		)
	)
	(footprint ""
		(layer "F.Cu")
		(at 325.862188 -393.47648 180)
		(property "Reference" "R951"
			(at 0 0 180)
			(layer "F.SilkS")
			(hide yes)
			(effects
				(font
					(size 1.27 1.27)
				)
			)
		)
		(property "Value" ""
			(at 0 0 180)
			(layer "F.Fab")
			(effects
				(font
					(size 1.27 1.27)
				)
			)
		)
		(duplicate_pad_numbers_are_jumpers no)
		(fp_line
			(start 0.7874 0.4064)
			(end -0.7874 0.4064)
			(stroke
				(width 0.1524)
				(type default)
			)
			(layer "F.SilkS")
		)
		(fp_line
			(start 0.7874 -0.4064)
			(end 0.7874 0.4064)
			(stroke
				(width 0.1524)
				(type default)
			)
			(layer "F.SilkS")
		)
		(fp_line
			(start -0.7874 0.4064)
			(end -0.7874 -0.4064)
			(stroke
				(width 0.1524)
				(type default)
			)
			(layer "F.SilkS")
		)
		(fp_line
			(start -0.7874 -0.4064)
			(end 0.7874 -0.4064)
			(stroke
				(width 0.1524)
				(type default)
			)
			(layer "F.SilkS")
		)
		(fp_line
			(start 0.67945 0.3048)
			(end 0.120396 0.3048)
			(stroke
				(width 0.1)
				(type default)
			)
			(layer "F.Fab")
		)
		(fp_line
			(start 0.67945 -0.3048)
			(end 0.67945 0.3048)
			(stroke
				(width 0.1)
				(type default)
			)
			(layer "F.Fab")
		)
		(fp_line
			(start 0.12065 -0.2794)
			(end 0.12065 -0.3048)
			(stroke
				(width 0.1)
				(type default)
			)
			(layer "F.Fab")
		)
		(fp_line
			(start 0.12065 -0.3048)
			(end 0.67945 -0.3048)
			(stroke
				(width 0.1)
				(type default)
			)
			(layer "F.Fab")
		)
		(fp_line
			(start 0.120396 0.3048)
			(end 0.120396 0.2794)
			(stroke
				(width 0.1)
				(type default)
			)
			(layer "F.Fab")
		)
		(fp_line
			(start 0.120396 0.2794)
			(end -0.12065 0.2794)
			(stroke
				(width 0.1)
				(type default)
			)
			(layer "F.Fab")
		)
		(fp_line
			(start -0.12065 0.3048)
			(end -0.67945 0.3048)
			(stroke
				(width 0.1)
				(type default)
			)
			(layer "F.Fab")
		)
		(fp_line
			(start -0.12065 0.2794)
			(end -0.12065 0.3048)
			(stroke
				(width 0.1)
				(type default)
			)
			(layer "F.Fab")
		)
		(fp_line
			(start -0.12065 -0.2794)
			(end 0.12065 -0.2794)
			(stroke
				(width 0.1)
				(type default)
			)
			(layer "F.Fab")
		)
		(fp_line
			(start -0.12065 -0.305054)
			(end -0.12065 -0.2794)
			(stroke
				(width 0.1)
				(type default)
			)
			(layer "F.Fab")
		)
		(fp_line
			(start -0.67945 0.3048)
			(end -0.67945 -0.305054)
			(stroke
				(width 0.1)
				(type default)
			)
			(layer "F.Fab")
		)
		(fp_line
			(start -0.67945 -0.305054)
			(end -0.12065 -0.305054)
			(stroke
				(width 0.1)
				(type default)
			)
			(layer "F.Fab")
		)
		(pad "1" smd rect
			(at -0.40005 0)
			(size 0.4572 0.508)
			(layers "F.Cu" "F.Mask" "F.Paste")
			(net "P1V8_CPU0_RT0_1A_1D")
		)
		(pad "2" smd rect
			(at 0.40005 0)
			(size 0.4572 0.508)
			(layers "F.Cu" "F.Mask" "F.Paste")
			(net "P1V8_CPU0_RT0_1A")
		)
	)
	(footprint ""
		(layer "F.Cu")
		(at 357.517192 -261.747762 -90)
		(property "Reference" "C2601"
			(at 0 0 270)
			(layer "F.SilkS")
			(hide yes)
			(effects
				(font
					(size 1.27 1.27)
				)
			)
		)
		(property "Value" ""
			(at 0 0 270)
			(layer "F.Fab")
			(effects
				(font
					(size 1.27 1.27)
				)
			)
		)
		(duplicate_pad_numbers_are_jumpers no)
		(fp_line
			(start -0.7874 0.4064)
			(end -0.7874 -0.4064)
			(stroke
				(width 0.1524)
				(type default)
			)
			(layer "F.SilkS")
		)
		(fp_line
			(start 0.7874 0.4064)
			(end -0.7874 0.4064)
			(stroke
				(width 0.1524)
				(type default)
			)
			(layer "F.SilkS")
		)
		(fp_line
			(start -0.7874 -0.4064)
			(end 0.7874 -0.4064)
			(stroke
				(width 0.1524)
				(type default)
			)
			(layer "F.SilkS")
		)
		(fp_line
			(start 0.7874 -0.4064)
			(end 0.7874 0.4064)
			(stroke
				(width 0.1524)
				(type default)
			)
			(layer "F.SilkS")
		)
		(fp_line
			(start -0.67945 0.3048)
			(end -0.67945 -0.305054)
			(stroke
				(width 0.1)
				(type default)
			)
			(layer "F.Fab")
		)
		(fp_line
			(start -0.12065 0.3048)
			(end -0.67945 0.3048)
			(stroke
				(width 0.1)
				(type default)
			)
			(layer "F.Fab")
		)
		(fp_line
			(start 0.120396 0.3048)
			(end 0.120396 0.2794)
			(stroke
				(width 0.1)
				(type default)
			)
			(layer "F.Fab")
		)
		(fp_line
			(start 0.67945 0.3048)
			(end 0.120396 0.3048)
			(stroke
				(width 0.1)
				(type default)
			)
			(layer "F.Fab")
		)
		(fp_line
			(start -0.12065 0.2794)
			(end -0.12065 0.3048)
			(stroke
				(width 0.1)
				(type default)
			)
			(layer "F.Fab")
		)
		(fp_line
			(start 0.120396 0.2794)
			(end -0.12065 0.2794)
			(stroke
				(width 0.1)
				(type default)
			)
			(layer "F.Fab")
		)
		(fp_line
			(start -0.12065 -0.2794)
			(end 0.12065 -0.2794)
			(stroke
				(width 0.1)
				(type default)
			)
			(layer "F.Fab")
		)
		(fp_line
			(start 0.12065 -0.2794)
			(end 0.12065 -0.3048)
			(stroke
				(width 0.1)
				(type default)
			)
			(layer "F.Fab")
		)
		(fp_line
			(start 0.12065 -0.3048)
			(end 0.67945 -0.3048)
			(stroke
				(width 0.1)
				(type default)
			)
			(layer "F.Fab")
		)
		(fp_line
			(start 0.67945 -0.3048)
			(end 0.67945 0.3048)
			(stroke
				(width 0.1)
				(type default)
			)
			(layer "F.Fab")
		)
		(fp_line
			(start -0.67945 -0.305054)
			(end -0.12065 -0.305054)
			(stroke
				(width 0.1)
				(type default)
			)
			(layer "F.Fab")
		)
		(fp_line
			(start -0.12065 -0.305054)
			(end -0.12065 -0.2794)
			(stroke
				(width 0.1)
				(type default)
			)
			(layer "F.Fab")
		)
		(pad "1" smd circle
			(at -0.40005 0 270)
			(size 0 0)
			(layers "F.Cu" "F.Mask" "F.Paste")
			(net "PVDD11_S3_P0")
		)
		(pad "2" smd circle
			(at 0.40005 0 270)
			(size 0 0)
			(layers "F.Cu" "F.Mask" "F.Paste")
			(net "GND")
		)
	)
)
